(kicad_pcb
	(version 20221018)
	(generator pcbnew)
	(general
    (thickness 1.7403)
  )
	(paper "A4")
	(title_block
    (title "Data Center RDIMM DDR4 Tester")
    (date "2024-09-30")
    (rev "1.2.4")
		(comment 9 "footprint 168 of 690 (U15), pads 352-438 of 676")
	)
	(layers
    (0 "F.Cu" signal)
    (1 "In1.Cu" power)
    (2 "In2.Cu" signal)
    (3 "In3.Cu" power)
    (4 "In4.Cu" power)
    (5 "In5.Cu" signal)
    (6 "In6.Cu" power)
    (7 "In7.Cu" signal)
    (8 "In8.Cu" power)
    (9 "In9.Cu" signal)
    (10 "In10.Cu" power)
    (31 "B.Cu" signal)
    (32 "B.Adhes" user "B.Adhesive")
    (33 "F.Adhes" user "F.Adhesive")
    (34 "B.Paste" user)
    (35 "F.Paste" user)
    (36 "B.SilkS" user "B.Silkscreen")
    (37 "F.SilkS" user "F.Silkscreen")
    (38 "B.Mask" user)
    (39 "F.Mask" user)
    (40 "Dwgs.User" user "User.Drawings")
    (41 "Cmts.User" user "User.Comments")
    (42 "Eco1.User" user "User.Eco1")
    (43 "Eco2.User" user "User.Eco2")
    (44 "Edge.Cuts" user)
    (45 "Margin" user)
    (46 "B.CrtYd" user "B.Courtyard")
    (47 "F.CrtYd" user "F.Courtyard")
    (48 "B.Fab" user)
    (49 "F.Fab" user)
  )
	(footprint "data-center-rdimm-ddr4-tester-footprints:BGA-676_27x27mm_Layout26x26_P1X1mm"
    (layer "F.Cu")
    (at 183.635 90.06 180)
    (descr "FPGA XC7K160TFBG676")
    (tags "FPGA XC7K160TFBG676")
    (property "Author" "Antmicro")
    (property "License" "Apache-2.0")
    (property "MPN" "XC7K160T-FFG676")
    (property "Manufacturer" "AMD-Xilinx")
    (property "Sheetfile" "config-spi.kicad_sch")
    (property "Sheetname" "Config SPI flash")
    (property "ki_description" "Kintex®-7 Field Programmable Gate Array (FPGA) IC 300 4976640 65600 676-BBGA, FCBGA")
    (property "ki_keywords" "SMT, MICROCONTROLLER, IC, FPGA")
    (attr smd)
    (fp_text reference "U15" (at -10.675 -14.7 180) (layer "F.SilkS")
        (effects (font (size 0.7 0.7) (thickness 0.15)) (justify left bottom))
    )
    (fp_text value "XC7K160T-FFG676" (at 0 15.5 180) (layer "F.Fab")
        (effects (font (size 0.7 0.7) (thickness 0.15)) (justify left bottom))
    )
    (pad "H14" smd circle (at 0.499 -5.5 180) (size 0.5 0.5) (layers "F.Cu" "F.Paste" "F.Mask")
      (net 765 "unconnected-(U15E-IO_L5P_T0_16-PadH14)") (pinfunction "IO_L5P_T0_16") (pintype "bidirectional+no_connect") (die_length 10.698))
    (pad "H15" smd circle (at 1.499 -5.5 180) (size 0.5 0.5) (layers "F.Cu" "F.Paste" "F.Mask")
      (net 9 "GND") (pinfunction "GND") (pintype "passive"))
    (pad "H16" smd circle (at 2.499 -5.5 180) (size 0.5 0.5) (layers "F.Cu" "F.Paste" "F.Mask")
      (net 505 "FMC_IO_7_P") (pinfunction "IO_L7P_T1_AD10P_15") (pintype "bidirectional") (die_length 14.081))
    (pad "H17" smd circle (at 3.499 -5.5 180) (size 0.5 0.5) (layers "F.Cu" "F.Paste" "F.Mask")
      (net 506 "FMC_IO_14_P") (pinfunction "IO_L14P_T2_SRCC_15") (pintype "bidirectional") (die_length 11.166))
    (pad "H18" smd circle (at 4.499 -5.5 180) (size 0.5 0.5) (layers "F.Cu" "F.Paste" "F.Mask")
      (net 507 "FMC_IO_14_N") (pinfunction "IO_L14N_T2_SRCC_15") (pintype "bidirectional") (die_length 11.108))
    (pad "H19" smd circle (at 5.499 -5.5 180) (size 0.5 0.5) (layers "F.Cu" "F.Paste" "F.Mask")
      (net 514 "FMC_IO_18_P") (pinfunction "IO_L18P_T2_A24_15") (pintype "bidirectional") (die_length 11.791))
    (pad "H20" smd circle (at 6.499 -5.5 180) (size 0.5 0.5) (layers "F.Cu" "F.Paste" "F.Mask")
      (net 143 "3V3_SYS") (pinfunction "VCCO_15") (pintype "passive"))
    (pad "H21" smd circle (at 7.499 -5.5 180) (size 0.5 0.5) (layers "F.Cu" "F.Paste" "F.Mask")
      (net 766 "unconnected-(U15C-IO_L19P_T3_A10_D26_14-PadH21)") (pinfunction "IO_L19P_T3_A10_D26_14") (pintype "bidirectional+no_connect") (die_length 18.685))
    (pad "H22" smd circle (at 8.499 -5.5 180) (size 0.5 0.5) (layers "F.Cu" "F.Paste" "F.Mask")
      (net 907 "FMC_SCL_3V3") (pinfunction "IO_L21N_T3_DQS_A06_D22_14") (pintype "bidirectional") (die_length 20.841))
    (pad "H23" smd circle (at 9.499 -5.5 180) (size 0.5 0.5) (layers "F.Cu" "F.Paste" "F.Mask")
      (net 767 "unconnected-(U15C-IO_L20P_T3_A08_D24_14-PadH23)") (pinfunction "IO_L20P_T3_A08_D24_14") (pintype "bidirectional+no_connect") (die_length 18.73))
    (pad "H24" smd circle (at 10.499 -5.5 180) (size 0.5 0.5) (layers "F.Cu" "F.Paste" "F.Mask")
      (net 768 "unconnected-(U15C-IO_L20N_T3_A07_D23_14-PadH24)") (pinfunction "IO_L20N_T3_A07_D23_14") (pintype "bidirectional+no_connect") (die_length 17.912))
    (pad "H25" smd circle (at 11.499 -5.5 180) (size 0.5 0.5) (layers "F.Cu" "F.Paste" "F.Mask")
      (net 9 "GND") (pinfunction "GND") (pintype "passive"))
    (pad "H26" smd circle (at 12.499 -5.5 180) (size 0.5 0.5) (layers "F.Cu" "F.Paste" "F.Mask")
      (net 800 "FPGA_VTT_CNTL") (pinfunction "IO_L18N_T2_A11_D27_14") (pintype "bidirectional") (die_length 19.909))
    (pad "J1" smd circle (at -12.5 -4.5 180) (size 0.5 0.5) (layers "F.Cu" "F.Paste" "F.Mask")
      (net 9 "GND") (pinfunction "GND") (pintype "passive"))
    (pad "J2" smd circle (at -11.5 -4.5 180) (size 0.5 0.5) (layers "F.Cu" "F.Paste" "F.Mask")
      (net 9 "GND") (pinfunction "GND") (pintype "passive"))
    (pad "J3" smd circle (at -10.5 -4.5 180) (size 0.5 0.5) (layers "F.Cu" "F.Paste" "F.Mask")
      (net 639 "GTX_RX4_N") (pinfunction "MGTXRXN3_115") (pintype "bidirectional") (die_length 11.806))
    (pad "J4" smd circle (at -9.5 -4.5 180) (size 0.5 0.5) (layers "F.Cu" "F.Paste" "F.Mask")
      (net 638 "GTX_RX4_P") (pinfunction "MGTXRXP3_115") (pintype "bidirectional") (die_length 11.935))
    (pad "J5" smd circle (at -8.5 -4.5 180) (size 0.5 0.5) (layers "F.Cu" "F.Paste" "F.Mask")
      (net 9 "GND") (pinfunction "GND") (pintype "passive"))
    (pad "J6" smd circle (at -7.5 -4.5 180) (size 0.5 0.5) (layers "F.Cu" "F.Paste" "F.Mask")
      (net 147 "1V0_SYS") (pinfunction "MGTAVCC") (pintype "passive"))
    (pad "J7" smd circle (at -6.5 -4.5 180) (size 0.5 0.5) (layers "F.Cu" "F.Paste" "F.Mask")
      (net 25 "DONE") (pinfunction "DONE_0") (pintype "bidirectional") (die_length 33.726))
    (pad "J8" smd circle (at -5.5 -4.5 180) (size 0.5 0.5) (layers "F.Cu" "F.Paste" "F.Mask")
      (net 769 "unconnected-(U15E-IO_0_16-PadJ8)") (pinfunction "IO_0_16") (pintype "bidirectional+no_connect") (die_length 17.143))
    (pad "J9" smd circle (at -4.5 -4.5 180) (size 0.5 0.5) (layers "F.Cu" "F.Paste" "F.Mask")
      (net 147 "1V0_SYS") (pinfunction "VCCINT") (pintype "power_in"))
    (pad "J10" smd circle (at -3.5 -4.5 180) (size 0.5 0.5) (layers "F.Cu" "F.Paste" "F.Mask")
      (net 770 "unconnected-(U15E-IO_L4N_T0_16-PadJ10)") (pinfunction "IO_L4N_T0_16") (pintype "bidirectional+no_connect") (die_length 16.988))
    (pad "J11" smd circle (at -2.5 -4.5 180) (size 0.5 0.5) (layers "F.Cu" "F.Paste" "F.Mask")
      (net 771 "unconnected-(U15E-IO_L4P_T0_16-PadJ11)") (pinfunction "IO_L4P_T0_16") (pintype "bidirectional+no_connect") (die_length 16.441))
    (pad "J12" smd circle (at -1.5 -4.5 180) (size 0.5 0.5) (layers "F.Cu" "F.Paste" "F.Mask")
      (net 9 "GND") (pinfunction "GND") (pintype "passive"))
    (pad "J13" smd circle (at -0.5 -4.5 180) (size 0.5 0.5) (layers "F.Cu" "F.Paste" "F.Mask")
      (net 772 "unconnected-(U15E-IO_L3P_T0_DQS_16-PadJ13)") (pinfunction "IO_L3P_T0_DQS_16") (pintype "bidirectional+no_connect") (die_length 12.775))
    (pad "J14" smd circle (at 0.499 -4.5 180) (size 0.5 0.5) (layers "F.Cu" "F.Paste" "F.Mask")
      (net 773 "unconnected-(U15E-IO_25_16-PadJ14)") (pinfunction "IO_25_16") (pintype "bidirectional+no_connect") (die_length 13.82))
    (pad "J15" smd circle (at 1.499 -4.5 180) (size 0.5 0.5) (layers "F.Cu" "F.Paste" "F.Mask")
      (net 515 "FMC_IO_9_P") (pinfunction "IO_L9P_T1_DQS_AD11P_15") (pintype "bidirectional") (die_length 15.384))
    (pad "J16" smd circle (at 2.499 -4.5 180) (size 0.5 0.5) (layers "F.Cu" "F.Paste" "F.Mask")
      (net 516 "FMC_IO_9_N") (pinfunction "IO_L9N_T1_DQS_AD11N_15") (pintype "bidirectional") (die_length 14.742))
    (pad "J17" smd circle (at 3.499 -4.5 180) (size 0.5 0.5) (layers "F.Cu" "F.Paste" "F.Mask")
      (net 143 "3V3_SYS") (pinfunction "VCCO_15") (pintype "passive"))
    (pad "J18" smd circle (at 4.499 -4.5 180) (size 0.5 0.5) (layers "F.Cu" "F.Paste" "F.Mask")
      (net 517 "FMC_IO_20_P") (pinfunction "IO_L20P_T3_A20_15") (pintype "bidirectional") (die_length 11.906))
    (pad "J19" smd circle (at 5.499 -4.5 180) (size 0.5 0.5) (layers "F.Cu" "F.Paste" "F.Mask")
      (net 518 "FMC_IO_20_N") (pinfunction "IO_L20N_T3_A19_15") (pintype "bidirectional") (die_length 11.025))
    (pad "J20" smd circle (at 6.499 -4.5 180) (size 0.5 0.5) (layers "F.Cu" "F.Paste" "F.Mask")
      (net 528 "FMC_IO_19_N") (pinfunction "IO_L19N_T3_A21_VREF_15") (pintype "bidirectional") (die_length 9.831))
    (pad "J21" smd circle (at 7.499 -4.5 180) (size 0.5 0.5) (layers "F.Cu" "F.Paste" "F.Mask")
      (net 774 "unconnected-(U15C-IO_L21P_T3_DQS_14-PadJ21)") (pinfunction "IO_L21P_T3_DQS_14") (pintype "bidirectional+no_connect") (die_length 21.288))
    (pad "J22" smd circle (at 8.499 -4.5 180) (size 0.5 0.5) (layers "F.Cu" "F.Paste" "F.Mask")
      (net 9 "GND") (pinfunction "GND") (pintype "passive"))
    (pad "J23" smd circle (at 9.499 -4.5 180) (size 0.5 0.5) (layers "F.Cu" "F.Paste" "F.Mask")
      (net 775 "unconnected-(U15C-IO_L24N_T3_A00_D16_14-PadJ23)") (pinfunction "IO_L24N_T3_A00_D16_14") (pintype "bidirectional+no_connect") (die_length 18.062))
    (pad "J24" smd circle (at 10.499 -4.5 180) (size 0.5 0.5) (layers "F.Cu" "F.Paste" "F.Mask")
      (net 776 "unconnected-(U15C-IO_L22P_T3_A05_D21_14-PadJ24)") (pinfunction "IO_L22P_T3_A05_D21_14") (pintype "bidirectional+no_connect") (die_length 17.661))
    (pad "J25" smd circle (at 11.499 -4.5 180) (size 0.5 0.5) (layers "F.Cu" "F.Paste" "F.Mask")
      (net 777 "unconnected-(U15C-IO_L22N_T3_A04_D20_14-PadJ25)") (pinfunction "IO_L22N_T3_A04_D20_14") (pintype "bidirectional+no_connect") (die_length 17.645))
    (pad "J26" smd circle (at 12.499 -4.5 180) (size 0.5 0.5) (layers "F.Cu" "F.Paste" "F.Mask")
      (net 799 "FPGA_SLP_S4") (pinfunction "IO_L18P_T2_A12_D28_14") (pintype "bidirectional") (die_length 21.026))
    (pad "K1" smd circle (at -12.5 -3.5 180) (size 0.5 0.5) (layers "F.Cu" "F.Paste" "F.Mask")
      (net 483 "GTX_TX5_N") (pinfunction "MGTXTXN2_115") (pintype "bidirectional") (die_length 13.554))
    (pad "K2" smd circle (at -11.5 -3.5 180) (size 0.5 0.5) (layers "F.Cu" "F.Paste" "F.Mask")
      (net 481 "GTX_TX5_P") (pinfunction "MGTXTXP2_115") (pintype "bidirectional") (die_length 13.554))
    (pad "K3" smd circle (at -10.5 -3.5 180) (size 0.5 0.5) (layers "F.Cu" "F.Paste" "F.Mask")
      (net 9 "GND") (pinfunction "GND") (pintype "passive"))
    (pad "K4" smd circle (at -9.5 -3.5 180) (size 0.5 0.5) (layers "F.Cu" "F.Paste" "F.Mask")
      (net 9 "GND") (pinfunction "GND") (pintype "passive"))
    (pad "K5" smd circle (at -8.5 -3.5 180) (size 0.5 0.5) (layers "F.Cu" "F.Paste" "F.Mask")
      (net 884 "/FPGA banks 115-116/GTR_REFCLK1_N") (pinfunction "MGTREFCLK1N_115") (pintype "bidirectional") (die_length 11.876))
    (pad "K6" smd circle (at -7.5 -3.5 180) (size 0.5 0.5) (layers "F.Cu" "F.Paste" "F.Mask")
      (net 883 "/FPGA banks 115-116/GTR_REFCLK1_P") (pinfunction "MGTREFCLK1P_115") (pintype "bidirectional") (die_length 11.561))
    (pad "K7" smd circle (at -6.5 -3.5 180) (size 0.5 0.5) (layers "F.Cu" "F.Paste" "F.Mask")
      (net 9 "GND") (pinfunction "GND") (pintype "passive"))
    (pad "K8" smd circle (at -5.5 -3.5 180) (size 0.5 0.5) (layers "F.Cu" "F.Paste" "F.Mask")
      (net 147 "1V0_SYS") (pinfunction "VCCINT") (pintype "passive"))
    (pad "K9" smd circle (at -4.5 -3.5 180) (size 0.5 0.5) (layers "F.Cu" "F.Paste" "F.Mask")
      (net 9 "GND") (pinfunction "GND") (pintype "passive"))
    (pad "K10" smd circle (at -3.5 -3.5 180) (size 0.5 0.5) (layers "F.Cu" "F.Paste" "F.Mask")
      (net 147 "1V0_SYS") (pinfunction "VCCINT") (pintype "passive"))
    (pad "K11" smd circle (at -2.5 -3.5 180) (size 0.5 0.5) (layers "F.Cu" "F.Paste" "F.Mask")
      (net 9 "GND") (pinfunction "GND") (pintype "passive"))
    (pad "K12" smd circle (at -1.5 -3.5 180) (size 0.5 0.5) (layers "F.Cu" "F.Paste" "F.Mask")
      (net 147 "1V0_SYS") (pinfunction "VCCINT") (pintype "passive"))
    (pad "K13" smd circle (at -0.5 -3.5 180) (size 0.5 0.5) (layers "F.Cu" "F.Paste" "F.Mask")
      (net 9 "GND") (pinfunction "GND") (pintype "passive"))
    (pad "K14" smd circle (at 0.499 -3.5 180) (size 0.5 0.5) (layers "F.Cu" "F.Paste" "F.Mask")
      (net 147 "1V0_SYS") (pinfunction "VCCINT") (pintype "passive"))
    (pad "K15" smd circle (at 1.499 -3.5 180) (size 0.5 0.5) (layers "F.Cu" "F.Paste" "F.Mask")
      (net 529 "FMC_IO_0") (pinfunction "IO_0_15") (pintype "bidirectional") (die_length 6.731))
    (pad "K16" smd circle (at 2.499 -3.5 180) (size 0.5 0.5) (layers "F.Cu" "F.Paste" "F.Mask")
      (net 538 "FMC_IO_22_P") (pinfunction "IO_L22P_T3_A17_15") (pintype "bidirectional") (die_length 6.898))
    (pad "K17" smd circle (at 3.499 -3.5 180) (size 0.5 0.5) (layers "F.Cu" "F.Paste" "F.Mask")
      (net 539 "FMC_IO_22_N") (pinfunction "IO_L22N_T3_A16_15") (pintype "bidirectional") (die_length 7.2))
    (pad "K18" smd circle (at 4.499 -3.5 180) (size 0.5 0.5) (layers "F.Cu" "F.Paste" "F.Mask")
      (net 809 "FMC_IO_24_N") (pinfunction "IO_L24N_T3_RS0_15") (pintype "bidirectional") (die_length 7.112))
    (pad "K19" smd circle (at 5.499 -3.5 180) (size 0.5 0.5) (layers "F.Cu" "F.Paste" "F.Mask")
      (net 9 "GND") (pinfunction "GND") (pintype "passive"))
    (pad "K20" smd circle (at 6.499 -3.5 180) (size 0.5 0.5) (layers "F.Cu" "F.Paste" "F.Mask")
      (net 810 "FMC_IO_19_P") (pinfunction "IO_L19P_T3_A22_15") (pintype "bidirectional") (die_length 8.708))
    (pad "K21" smd circle (at 7.499 -3.5 180) (size 0.5 0.5) (layers "F.Cu" "F.Paste" "F.Mask")
      (net 778 "unconnected-(U15C-IO_0_14-PadK21)") (pinfunction "IO_0_14") (pintype "bidirectional+no_connect") (die_length 10.072))
    (pad "K22" smd circle (at 8.499 -3.5 180) (size 0.5 0.5) (layers "F.Cu" "F.Paste" "F.Mask")
      (net 779 "unconnected-(U15C-IO_L23N_T3_A02_D18_14-PadK22)") (pinfunction "IO_L23N_T3_A02_D18_14") (pintype "bidirectional+no_connect") (die_length 16.883))
    (pad "K23" smd circle (at 9.499 -3.5 180) (size 0.5 0.5) (layers "F.Cu" "F.Paste" "F.Mask")
      (net 780 "unconnected-(U15C-IO_L24P_T3_A01_D17_14-PadK23)") (pinfunction "IO_L24P_T3_A01_D17_14") (pintype "bidirectional+no_connect") (die_length 17.632))
    (pad "K24" smd circle (at 10.499 -3.5 180) (size 0.5 0.5) (layers "F.Cu" "F.Paste" "F.Mask")
      (net 77 "VDDQ") (pinfunction "VCCO_13") (pintype "power_in"))
    (pad "K25" smd circle (at 11.499 -3.5 180) (size 0.5 0.5) (layers "F.Cu" "F.Paste" "F.Mask")
      (net 781 "unconnected-(U15B-IO_L1P_T0_13-PadK25)") (pinfunction "IO_L1P_T0_13") (pintype "bidirectional+no_connect") (die_length 16.886))
    (pad "K26" smd circle (at 12.499 -3.5 180) (size 0.5 0.5) (layers "F.Cu" "F.Paste" "F.Mask")
      (net 782 "unconnected-(U15B-IO_L1N_T0_13-PadK26)") (pinfunction "IO_L1N_T0_13") (pintype "bidirectional+no_connect") (die_length 17.592))
    (pad "L1" smd circle (at -12.5 -2.5 180) (size 0.5 0.5) (layers "F.Cu" "F.Paste" "F.Mask")
      (net 9 "GND") (pinfunction "GND") (pintype "passive"))
    (pad "L2" smd circle (at -11.5 -2.5 180) (size 0.5 0.5) (layers "F.Cu" "F.Paste" "F.Mask")
      (net 306 "1V2_SYS") (pinfunction "MGTAVTT") (pintype "passive"))
    (pad "L3" smd circle (at -10.5 -2.5 180) (size 0.5 0.5) (layers "F.Cu" "F.Paste" "F.Mask")
      (net 641 "GTX_RX5_N") (pinfunction "MGTXRXN2_115") (pintype "bidirectional") (die_length 11.935))
    (pad "L4" smd circle (at -9.5 -2.5 180) (size 0.5 0.5) (layers "F.Cu" "F.Paste" "F.Mask")
      (net 640 "GTX_RX5_P") (pinfunction "MGTXRXP2_115") (pintype "bidirectional") (die_length 12.06))
    (pad "L5" smd circle (at -8.5 -2.5 180) (size 0.5 0.5) (layers "F.Cu" "F.Paste" "F.Mask")
      (net 9 "GND") (pinfunction "GND") (pintype "passive"))
    (pad "L6" smd circle (at -7.5 -2.5 180) (size 0.5 0.5) (layers "F.Cu" "F.Paste" "F.Mask")
      (net 147 "1V0_SYS") (pinfunction "MGTAVCC") (pintype "passive"))
    (pad "L7" smd circle (at -6.5 -2.5 180) (size 0.5 0.5) (layers "F.Cu" "F.Paste" "F.Mask")
      (net 143 "3V3_SYS") (pinfunction "VCCO_0") (pintype "power_in"))
    (pad "L8" smd circle (at -5.5 -2.5 180) (size 0.5 0.5) (layers "F.Cu" "F.Paste" "F.Mask")
      (net 12 "TCK_JTAG") (pinfunction "TCK_0") (pintype "bidirectional") (die_length 14.628))
    (pad "L9" smd circle (at -4.5 -2.5 180) (size 0.5 0.5) (layers "F.Cu" "F.Paste" "F.Mask")
      (net 147 "1V0_SYS") (pinfunction "VCCINT") (pintype "passive"))
    (pad "L10" smd circle (at -3.5 -2.5 180) (size 0.5 0.5) (layers "F.Cu" "F.Paste" "F.Mask")
      (net 9 "GND") (pinfunction "GND") (pintype "passive"))
    (pad "L11" smd circle (at -2.5 -2.5 180) (size 0.5 0.5) (layers "F.Cu" "F.Paste" "F.Mask")
      (net 144 "1V8_SYS") (pinfunction "VCCAUX") (pintype "power_in"))
    (pad "L12" smd circle (at -1.5 -2.5 180) (size 0.5 0.5) (layers "F.Cu" "F.Paste" "F.Mask")
      (net 9 "GND") (pinfunction "GND") (pintype "passive"))
    (pad "L13" smd circle (at -0.5 -2.5 180) (size 0.5 0.5) (layers "F.Cu" "F.Paste" "F.Mask")
      (net 147 "1V0_SYS") (pinfunction "VCCINT") (pintype "passive"))
    (pad "L14" smd circle (at 0.499 -2.5 180) (size 0.5 0.5) (layers "F.Cu" "F.Paste" "F.Mask")
      (net 9 "GND") (pinfunction "GND") (pintype "passive"))
    (pad "L15" smd circle (at 1.499 -2.5 180) (size 0.5 0.5) (layers "F.Cu" "F.Paste" "F.Mask")
      (net 147 "1V0_SYS") (pinfunction "VCCINT") (pintype "passive"))
    (pad "L16" smd circle (at 2.499 -2.5 180) (size 0.5 0.5) (layers "F.Cu" "F.Paste" "F.Mask")
      (net 9 "GND") (pinfunction "GND") (pintype "passive"))
    (pad "L17" smd circle (at 3.499 -2.5 180) (size 0.5 0.5) (layers "F.Cu" "F.Paste" "F.Mask")
      (net 811 "FMC_IO_24_P") (pinfunction "IO_L24P_T3_RS1_15") (pintype "bidirectional") (die_length 6.318))
    (pad "L18" smd circle (at 4.499 -2.5 180) (size 0.5 0.5) (layers "F.Cu" "F.Paste" "F.Mask")
      (net 812 "FMC_IO_23_N") (pinfunction "IO_L23N_T3_FWE_B_15") (pintype "bidirectional") (die_length 7.658))
    (pad "L19" smd circle (at 5.499 -2.5 180) (size 0.5 0.5) (layers "F.Cu" "F.Paste" "F.Mask")
      (net 813 "FMC_IO_21_P") (pinfunction "IO_L21P_T3_DQS_15") (pintype "bidirectional") (die_length 7.664))
    (pad "L20" smd circle (at 6.499 -2.5 180) (size 0.5 0.5) (layers "F.Cu" "F.Paste" "F.Mask")
      (net 814 "FMC_IO_21_N") (pinfunction "IO_L21N_T3_DQS_A18_15") (pintype "bidirectional") (die_length 7.681))
    (pad "L21" smd circle (at 7.499 -2.5 180) (size 0.5 0.5) (layers "F.Cu" "F.Paste" "F.Mask")
      (net 143 "3V3_SYS") (pinfunction "VCCO_14") (pintype "passive"))
    (pad "L22" smd circle (at 8.499 -2.5 180) (size 0.5 0.5) (layers "F.Cu" "F.Paste" "F.Mask")
      (net 783 "unconnected-(U15C-IO_L23P_T3_A03_D19_14-PadL22)") (pinfunction "IO_L23P_T3_A03_D19_14") (pintype "bidirectional+no_connect") (die_length 16.198))
  )
)
